(kicad_pcb
	(version 20260206)
	(generator "pcbnew")
	(generator_version "10.0")
	(general
		(thickness 1.6)
		(legacy_teardrops no)
	)
	(paper "A4")
	(title_block
		(title "04192023_DAF0TMB3IC0_F0TG_MB_C_brd_V02_OCP.brd")
		(comment 1 "Grand Teton / footprints 1511-1517 of 8354")
	)
	(layers
		(0 "F.Cu" signal "TOP")
		(4 "In1.Cu" signal "GND")
		(6 "In2.Cu" signal "IN1")
		(8 "In3.Cu" signal "GND1")
		(10 "In4.Cu" signal "IN2")
		(12 "In5.Cu" signal "GND2")
		(14 "In6.Cu" signal "IN3")
		(16 "In7.Cu" signal "GND3")
		(18 "In8.Cu" signal "VCC")
		(20 "In9.Cu" signal "VCC1")
		(22 "In10.Cu" signal "GND4")
		(24 "In11.Cu" signal "IN4")
		(26 "In12.Cu" signal "GND5")
		(28 "In13.Cu" signal "IN5")
		(30 "In14.Cu" signal "GND6")
		(32 "In15.Cu" signal "IN6")
		(34 "In16.Cu" signal "GND7")
		(2 "B.Cu" signal "BOTTOM")
		(9 "F.Adhes" user "F.Adhesive")
		(11 "B.Adhes" user "B.Adhesive")
		(13 "F.Paste" user "Package Geometry/Pastemask Top")
		(15 "B.Paste" user "Package Geometry/Pastemask Bottom")
		(5 "F.SilkS" user "Ref Des/Silkscreen Top")
		(7 "B.SilkS" user "Ref Des/Silkscreen Bottom")
		(1 "F.Mask" user "Board Geometry/Soldermask Top")
		(3 "B.Mask" user "Board Geometry/Soldermask Bottom")
		(17 "Dwgs.User" user "User.Drawings")
		(19 "Cmts.User" user "User.Comments")
		(21 "Eco1.User" user "User.Eco1")
		(23 "Eco2.User" user "User.Eco2")
		(25 "Edge.Cuts" user "Board Geometry/Outline")
		(27 "Margin" user)
		(31 "F.CrtYd" user "Package Geometry/Place Bound Top")
		(29 "B.CrtYd" user "Package Geometry/Place Bound Bottom")
		(35 "F.Fab" user "Ref Des/Assembly Top")
		(33 "B.Fab" user "Ref Des/Assembly Bottom")
	)
	(footprint ""
		(layer "F.Cu")
		(at 117.330474 -55.036212 90)
		(property "Reference" "R1730"
			(at 0 0 90)
			(layer "F.SilkS")
			(hide yes)
			(effects
				(font
					(size 1.27 1.27)
				)
			)
		)
		(property "Value" ""
			(at 0 0 90)
			(layer "F.Fab")
			(effects
				(font
					(size 1.27 1.27)
				)
			)
		)
		(duplicate_pad_numbers_are_jumpers no)
		(fp_line
			(start 0.7874 -0.4064)
			(end 0.7874 0.4064)
			(stroke
				(width 0.1524)
				(type default)
			)
			(layer "F.SilkS")
		)
		(fp_line
			(start -0.7874 -0.4064)
			(end 0.7874 -0.4064)
			(stroke
				(width 0.1524)
				(type default)
			)
			(layer "F.SilkS")
		)
		(fp_line
			(start 0.7874 0.4064)
			(end -0.7874 0.4064)
			(stroke
				(width 0.1524)
				(type default)
			)
			(layer "F.SilkS")
		)
		(fp_line
			(start -0.7874 0.4064)
			(end -0.7874 -0.4064)
			(stroke
				(width 0.1524)
				(type default)
			)
			(layer "F.SilkS")
		)
		(fp_line
			(start -0.12065 -0.305054)
			(end -0.12065 -0.2794)
			(stroke
				(width 0.1)
				(type default)
			)
			(layer "F.Fab")
		)
		(fp_line
			(start -0.67945 -0.305054)
			(end -0.12065 -0.305054)
			(stroke
				(width 0.1)
				(type default)
			)
			(layer "F.Fab")
		)
		(fp_line
			(start 0.67945 -0.3048)
			(end 0.67945 0.3048)
			(stroke
				(width 0.1)
				(type default)
			)
			(layer "F.Fab")
		)
		(fp_line
			(start 0.12065 -0.3048)
			(end 0.67945 -0.3048)
			(stroke
				(width 0.1)
				(type default)
			)
			(layer "F.Fab")
		)
		(fp_line
			(start 0.12065 -0.2794)
			(end 0.12065 -0.3048)
			(stroke
				(width 0.1)
				(type default)
			)
			(layer "F.Fab")
		)
		(fp_line
			(start -0.12065 -0.2794)
			(end 0.12065 -0.2794)
			(stroke
				(width 0.1)
				(type default)
			)
			(layer "F.Fab")
		)
		(fp_line
			(start 0.120396 0.2794)
			(end -0.12065 0.2794)
			(stroke
				(width 0.1)
				(type default)
			)
			(layer "F.Fab")
		)
		(fp_line
			(start -0.12065 0.2794)
			(end -0.12065 0.3048)
			(stroke
				(width 0.1)
				(type default)
			)
			(layer "F.Fab")
		)
		(fp_line
			(start 0.67945 0.3048)
			(end 0.120396 0.3048)
			(stroke
				(width 0.1)
				(type default)
			)
			(layer "F.Fab")
		)
		(fp_line
			(start 0.120396 0.3048)
			(end 0.120396 0.2794)
			(stroke
				(width 0.1)
				(type default)
			)
			(layer "F.Fab")
		)
		(fp_line
			(start -0.12065 0.3048)
			(end -0.67945 0.3048)
			(stroke
				(width 0.1)
				(type default)
			)
			(layer "F.Fab")
		)
		(fp_line
			(start -0.67945 0.3048)
			(end -0.67945 -0.305054)
			(stroke
				(width 0.1)
				(type default)
			)
			(layer "F.Fab")
		)
		(pad "1" smd circle
			(at -0.40005 0 90)
			(size 0 0)
			(layers "F.Cu" "F.Mask" "F.Paste")
			(net "P3V3_AUX")
		)
		(pad "2" smd circle
			(at 0.40005 0 90)
			(size 0 0)
			(layers "F.Cu" "F.Mask" "F.Paste")
			(net "SCM_JTAG_MUX_S1")
		)
	)
	(footprint ""
		(layer "F.Cu")
		(at 99.080828 -394.3604 -90)
		(property "Reference" "R6731"
			(at 0 0 270)
			(layer "F.SilkS")
			(hide yes)
			(effects
				(font
					(size 1.27 1.27)
				)
			)
		)
		(property "Value" ""
			(at 0 0 270)
			(layer "F.Fab")
			(effects
				(font
					(size 1.27 1.27)
				)
			)
		)
		(duplicate_pad_numbers_are_jumpers no)
		(fp_line
			(start -0.32512 0.175006)
			(end -0.32512 -0.175006)
			(stroke
				(width 0.1)
				(type default)
			)
			(layer "F.Fab")
		)
		(fp_line
			(start 0.32512 0.175006)
			(end -0.32512 0.175006)
			(stroke
				(width 0.1)
				(type default)
			)
			(layer "F.Fab")
		)
		(fp_line
			(start -0.32512 -0.175006)
			(end 0.32512 -0.175006)
			(stroke
				(width 0.1)
				(type default)
			)
			(layer "F.Fab")
		)
		(fp_line
			(start 0.32512 -0.175006)
			(end 0.32512 0.175006)
			(stroke
				(width 0.1)
				(type default)
			)
			(layer "F.Fab")
		)
		(pad "1" smd rect
			(at -0.2667 0 270)
			(size 0.3048 0.381)
			(layers "F.Cu" "F.Mask" "F.Paste")
			(net "RT_CPU1_P1_VQPS")
		)
		(pad "2" smd rect
			(at 0.2667 0 90)
			(size 0.3048 0.381)
			(layers "F.Cu" "F.Mask" "F.Paste")
			(net "GND")
		)
	)
	(footprint ""
		(layer "F.Cu")
		(at 57.40908 -52.53228)
		(property "Reference" "R1523"
			(at 0 0 0)
			(layer "F.SilkS")
			(hide yes)
			(effects
				(font
					(size 1.27 1.27)
				)
			)
		)
		(property "Value" ""
			(at 0 0 0)
			(layer "F.Fab")
			(effects
				(font
					(size 1.27 1.27)
				)
			)
		)
		(duplicate_pad_numbers_are_jumpers no)
		(fp_line
			(start -0.7874 -0.4064)
			(end 0.7874 -0.4064)
			(stroke
				(width 0.1524)
				(type default)
			)
			(layer "F.SilkS")
		)
		(fp_line
			(start -0.7874 0.4064)
			(end -0.7874 -0.4064)
			(stroke
				(width 0.1524)
				(type default)
			)
			(layer "F.SilkS")
		)
		(fp_line
			(start 0.7874 -0.4064)
			(end 0.7874 0.4064)
			(stroke
				(width 0.1524)
				(type default)
			)
			(layer "F.SilkS")
		)
		(fp_line
			(start 0.7874 0.4064)
			(end -0.7874 0.4064)
			(stroke
				(width 0.1524)
				(type default)
			)
			(layer "F.SilkS")
		)
		(fp_line
			(start -0.67945 -0.305054)
			(end -0.12065 -0.305054)
			(stroke
				(width 0.1)
				(type default)
			)
			(layer "F.Fab")
		)
		(fp_line
			(start -0.67945 0.3048)
			(end -0.67945 -0.305054)
			(stroke
				(width 0.1)
				(type default)
			)
			(layer "F.Fab")
		)
		(fp_line
			(start -0.12065 -0.305054)
			(end -0.12065 -0.2794)
			(stroke
				(width 0.1)
				(type default)
			)
			(layer "F.Fab")
		)
		(fp_line
			(start -0.12065 -0.2794)
			(end 0.12065 -0.2794)
			(stroke
				(width 0.1)
				(type default)
			)
			(layer "F.Fab")
		)
		(fp_line
			(start -0.12065 0.2794)
			(end -0.12065 0.3048)
			(stroke
				(width 0.1)
				(type default)
			)
			(layer "F.Fab")
		)
		(fp_line
			(start -0.12065 0.3048)
			(end -0.67945 0.3048)
			(stroke
				(width 0.1)
				(type default)
			)
			(layer "F.Fab")
		)
		(fp_line
			(start 0.120396 0.2794)
			(end -0.12065 0.2794)
			(stroke
				(width 0.1)
				(type default)
			)
			(layer "F.Fab")
		)
		(fp_line
			(start 0.120396 0.3048)
			(end 0.120396 0.2794)
			(stroke
				(width 0.1)
				(type default)
			)
			(layer "F.Fab")
		)
		(fp_line
			(start 0.12065 -0.3048)
			(end 0.67945 -0.3048)
			(stroke
				(width 0.1)
				(type default)
			)
			(layer "F.Fab")
		)
		(fp_line
			(start 0.12065 -0.2794)
			(end 0.12065 -0.3048)
			(stroke
				(width 0.1)
				(type default)
			)
			(layer "F.Fab")
		)
		(fp_line
			(start 0.67945 -0.3048)
			(end 0.67945 0.3048)
			(stroke
				(width 0.1)
				(type default)
			)
			(layer "F.Fab")
		)
		(fp_line
			(start 0.67945 0.3048)
			(end 0.120396 0.3048)
			(stroke
				(width 0.1)
				(type default)
			)
			(layer "F.Fab")
		)
		(pad "1" smd circle
			(at -0.40005 0)
			(size 0 0)
			(layers "F.Cu" "F.Mask" "F.Paste")
			(net "HP_LVC3_OCP_V3_2_P12V_PWRGD")
		)
		(pad "2" smd circle
			(at 0.40005 0)
			(size 0 0)
			(layers "F.Cu" "F.Mask" "F.Paste")
			(net "HP_LVC3_OCP_V3_2_P12V_PWRGD_R2")
		)
	)
	(footprint ""
		(layer "F.Cu")
		(at 347.899736 -25.529286)
		(property "Reference" "C219"
			(at 0 0 0)
			(layer "F.SilkS")
			(hide yes)
			(effects
				(font
					(size 1.27 1.27)
				)
			)
		)
		(property "Value" ""
			(at 0 0 0)
			(layer "F.Fab")
			(effects
				(font
					(size 1.27 1.27)
				)
			)
		)
		(duplicate_pad_numbers_are_jumpers no)
		(fp_line
			(start -0.7874 -0.4064)
			(end 0.7874 -0.4064)
			(stroke
				(width 0.1524)
				(type default)
			)
			(layer "F.SilkS")
		)
		(fp_line
			(start -0.7874 0.4064)
			(end -0.7874 -0.4064)
			(stroke
				(width 0.1524)
				(type default)
			)
			(layer "F.SilkS")
		)
		(fp_line
			(start 0.7874 -0.4064)
			(end 0.7874 0.4064)
			(stroke
				(width 0.1524)
				(type default)
			)
			(layer "F.SilkS")
		)
		(fp_line
			(start 0.7874 0.4064)
			(end -0.7874 0.4064)
			(stroke
				(width 0.1524)
				(type default)
			)
			(layer "F.SilkS")
		)
		(fp_line
			(start -0.67945 -0.305054)
			(end -0.12065 -0.305054)
			(stroke
				(width 0.1)
				(type default)
			)
			(layer "F.Fab")
		)
		(fp_line
			(start -0.67945 0.3048)
			(end -0.67945 -0.305054)
			(stroke
				(width 0.1)
				(type default)
			)
			(layer "F.Fab")
		)
		(fp_line
			(start -0.12065 -0.305054)
			(end -0.12065 -0.2794)
			(stroke
				(width 0.1)
				(type default)
			)
			(layer "F.Fab")
		)
		(fp_line
			(start -0.12065 -0.2794)
			(end 0.12065 -0.2794)
			(stroke
				(width 0.1)
				(type default)
			)
			(layer "F.Fab")
		)
		(fp_line
			(start -0.12065 0.2794)
			(end -0.12065 0.3048)
			(stroke
				(width 0.1)
				(type default)
			)
			(layer "F.Fab")
		)
		(fp_line
			(start -0.12065 0.3048)
			(end -0.67945 0.3048)
			(stroke
				(width 0.1)
				(type default)
			)
			(layer "F.Fab")
		)
		(fp_line
			(start 0.120396 0.2794)
			(end -0.12065 0.2794)
			(stroke
				(width 0.1)
				(type default)
			)
			(layer "F.Fab")
		)
		(fp_line
			(start 0.120396 0.3048)
			(end 0.120396 0.2794)
			(stroke
				(width 0.1)
				(type default)
			)
			(layer "F.Fab")
		)
		(fp_line
			(start 0.12065 -0.3048)
			(end 0.67945 -0.3048)
			(stroke
				(width 0.1)
				(type default)
			)
			(layer "F.Fab")
		)
		(fp_line
			(start 0.12065 -0.2794)
			(end 0.12065 -0.3048)
			(stroke
				(width 0.1)
				(type default)
			)
			(layer "F.Fab")
		)
		(fp_line
			(start 0.67945 -0.3048)
			(end 0.67945 0.3048)
			(stroke
				(width 0.1)
				(type default)
			)
			(layer "F.Fab")
		)
		(fp_line
			(start 0.67945 0.3048)
			(end 0.120396 0.3048)
			(stroke
				(width 0.1)
				(type default)
			)
			(layer "F.Fab")
		)
		(pad "1" smd circle
			(at -0.40005 0)
			(size 0 0)
			(layers "F.Cu" "F.Mask" "F.Paste")
			(net "P1V8_AUX")
		)
		(pad "2" smd circle
			(at 0.40005 0)
			(size 0 0)
			(layers "F.Cu" "F.Mask" "F.Paste")
			(net "GND")
		)
	)
	(footprint ""
		(layer "F.Cu")
		(at 144.834864 -194.567048 90)
		(property "Reference" "PR169"
			(at 0 0 90)
			(layer "F.SilkS")
			(hide yes)
			(effects
				(font
					(size 1.27 1.27)
				)
			)
		)
		(property "Value" ""
			(at 0 0 90)
			(layer "F.Fab")
			(effects
				(font
					(size 1.27 1.27)
				)
			)
		)
		(duplicate_pad_numbers_are_jumpers no)
		(fp_line
			(start 0.7874 -0.4064)
			(end 0.7874 0.4064)
			(stroke
				(width 0.1524)
				(type default)
			)
			(layer "F.SilkS")
		)
		(fp_line
			(start -0.7874 -0.4064)
			(end 0.7874 -0.4064)
			(stroke
				(width 0.1524)
				(type default)
			)
			(layer "F.SilkS")
		)
		(fp_line
			(start 0.7874 0.4064)
			(end -0.7874 0.4064)
			(stroke
				(width 0.1524)
				(type default)
			)
			(layer "F.SilkS")
		)
		(fp_line
			(start -0.7874 0.4064)
			(end -0.7874 -0.4064)
			(stroke
				(width 0.1524)
				(type default)
			)
			(layer "F.SilkS")
		)
		(fp_line
			(start -0.12065 -0.305054)
			(end -0.12065 -0.2794)
			(stroke
				(width 0.1)
				(type default)
			)
			(layer "F.Fab")
		)
		(fp_line
			(start -0.67945 -0.305054)
			(end -0.12065 -0.305054)
			(stroke
				(width 0.1)
				(type default)
			)
			(layer "F.Fab")
		)
		(fp_line
			(start 0.67945 -0.3048)
			(end 0.67945 0.3048)
			(stroke
				(width 0.1)
				(type default)
			)
			(layer "F.Fab")
		)
		(fp_line
			(start 0.12065 -0.3048)
			(end 0.67945 -0.3048)
			(stroke
				(width 0.1)
				(type default)
			)
			(layer "F.Fab")
		)
		(fp_line
			(start 0.12065 -0.2794)
			(end 0.12065 -0.3048)
			(stroke
				(width 0.1)
				(type default)
			)
			(layer "F.Fab")
		)
		(fp_line
			(start -0.12065 -0.2794)
			(end 0.12065 -0.2794)
			(stroke
				(width 0.1)
				(type default)
			)
			(layer "F.Fab")
		)
		(fp_line
			(start 0.120396 0.2794)
			(end -0.12065 0.2794)
			(stroke
				(width 0.1)
				(type default)
			)
			(layer "F.Fab")
		)
		(fp_line
			(start -0.12065 0.2794)
			(end -0.12065 0.3048)
			(stroke
				(width 0.1)
				(type default)
			)
			(layer "F.Fab")
		)
		(fp_line
			(start 0.67945 0.3048)
			(end 0.120396 0.3048)
			(stroke
				(width 0.1)
				(type default)
			)
			(layer "F.Fab")
		)
		(fp_line
			(start 0.120396 0.3048)
			(end 0.120396 0.2794)
			(stroke
				(width 0.1)
				(type default)
			)
			(layer "F.Fab")
		)
		(fp_line
			(start -0.12065 0.3048)
			(end -0.67945 0.3048)
			(stroke
				(width 0.1)
				(type default)
			)
			(layer "F.Fab")
		)
		(fp_line
			(start -0.67945 0.3048)
			(end -0.67945 -0.305054)
			(stroke
				(width 0.1)
				(type default)
			)
			(layer "F.Fab")
		)
		(pad "1" smd circle
			(at -0.40005 0 90)
			(size 0 0)
			(layers "F.Cu" "F.Mask" "F.Paste")
			(net "SVID_PVDDCR_CPU0_P1_SVC_R")
		)
		(pad "2" smd circle
			(at 0.40005 0 90)
			(size 0 0)
			(layers "F.Cu" "F.Mask" "F.Paste")
			(net "SVID_PVDDCR_CPU0_P1_SVC")
		)
	)
	(footprint ""
		(layer "F.Cu")
		(at 200.914 -102.362 180)
		(property "Reference" "R8084"
			(at 0 0 180)
			(layer "F.SilkS")
			(hide yes)
			(effects
				(font
					(size 1.27 1.27)
				)
			)
		)
		(property "Value" ""
			(at 0 0 180)
			(layer "F.Fab")
			(effects
				(font
					(size 1.27 1.27)
				)
			)
		)
		(duplicate_pad_numbers_are_jumpers no)
		(fp_line
			(start 0.7874 0.4064)
			(end -0.7874 0.4064)
			(stroke
				(width 0.1524)
				(type default)
			)
			(layer "F.SilkS")
		)
		(fp_line
			(start 0.7874 -0.4064)
			(end 0.7874 0.4064)
			(stroke
				(width 0.1524)
				(type default)
			)
			(layer "F.SilkS")
		)
		(fp_line
			(start -0.7874 0.4064)
			(end -0.7874 -0.4064)
			(stroke
				(width 0.1524)
				(type default)
			)
			(layer "F.SilkS")
		)
		(fp_line
			(start -0.7874 -0.4064)
			(end 0.7874 -0.4064)
			(stroke
				(width 0.1524)
				(type default)
			)
			(layer "F.SilkS")
		)
		(fp_line
			(start 0.67945 0.3048)
			(end 0.120396 0.3048)
			(stroke
				(width 0.1)
				(type default)
			)
			(layer "F.Fab")
		)
		(fp_line
			(start 0.67945 -0.3048)
			(end 0.67945 0.3048)
			(stroke
				(width 0.1)
				(type default)
			)
			(layer "F.Fab")
		)
		(fp_line
			(start 0.12065 -0.2794)
			(end 0.12065 -0.3048)
			(stroke
				(width 0.1)
				(type default)
			)
			(layer "F.Fab")
		)
		(fp_line
			(start 0.12065 -0.3048)
			(end 0.67945 -0.3048)
			(stroke
				(width 0.1)
				(type default)
			)
			(layer "F.Fab")
		)
		(fp_line
			(start 0.120396 0.3048)
			(end 0.120396 0.2794)
			(stroke
				(width 0.1)
				(type default)
			)
			(layer "F.Fab")
		)
		(fp_line
			(start 0.120396 0.2794)
			(end -0.12065 0.2794)
			(stroke
				(width 0.1)
				(type default)
			)
			(layer "F.Fab")
		)
		(fp_line
			(start -0.12065 0.3048)
			(end -0.67945 0.3048)
			(stroke
				(width 0.1)
				(type default)
			)
			(layer "F.Fab")
		)
		(fp_line
			(start -0.12065 0.2794)
			(end -0.12065 0.3048)
			(stroke
				(width 0.1)
				(type default)
			)
			(layer "F.Fab")
		)
		(fp_line
			(start -0.12065 -0.2794)
			(end 0.12065 -0.2794)
			(stroke
				(width 0.1)
				(type default)
			)
			(layer "F.Fab")
		)
		(fp_line
			(start -0.12065 -0.305054)
			(end -0.12065 -0.2794)
			(stroke
				(width 0.1)
				(type default)
			)
			(layer "F.Fab")
		)
		(fp_line
			(start -0.67945 0.3048)
			(end -0.67945 -0.305054)
			(stroke
				(width 0.1)
				(type default)
			)
			(layer "F.Fab")
		)
		(fp_line
			(start -0.67945 -0.305054)
			(end -0.12065 -0.305054)
			(stroke
				(width 0.1)
				(type default)
			)
			(layer "F.Fab")
		)
		(pad "1" smd circle
			(at -0.40005 0 180)
			(size 0 0)
			(layers "F.Cu" "F.Mask" "F.Paste")
			(net "PWRGD_CHGL_CPU0_R1")
		)
		(pad "2" smd circle
			(at 0.40005 0 180)
			(size 0 0)
			(layers "F.Cu" "F.Mask" "F.Paste")
			(net "PWRGD_CHGL_CPU0_R2")
		)
	)
	(footprint ""
		(layer "F.Cu")
		(at 377.869958 -162.59683 180)
		(property "Reference" "PC491"
			(at 2.807716 -2.902712 0)
			(unlocked yes)
			(layer "F.SilkS")
			(effects
				(font
					(size 0.7874 0.5842)
					(thickness 0.1524)
				)
				(justify left)
			)
		)
		(property "Value" ""
			(at 0 0 180)
			(layer "F.Fab")
			(effects
				(font
					(size 1.27 1.27)
				)
			)
		)
		(duplicate_pad_numbers_are_jumpers no)
		(fp_line
			(start -3.400044 1.249934)
			(end 3.400044 1.249934)
			(stroke
				(width 0.1524)
				(type default)
			)
			(layer "F.SilkS")
		)
		(fp_circle
			(center 0 1.249934)
			(end -3.400044 1.249934)
			(stroke
				(width 0.1524)
				(type default)
			)
			(fill no)
			(layer "F.SilkS")
		)
		(fp_poly
			(pts
				(arc
					(start 3.400044 1.249934)
					(mid 0 4.649978)
					(end -3.400044 1.249934)
				)
			)
			(stroke
				(width 0)
				(type default)
			)
			(fill yes)
			(layer "F.SilkS")
		)
		(fp_circle
			(center 0 1.249934)
			(end -3.400044 1.249934)
			(stroke
				(width 0.1)
				(type default)
			)
			(fill no)
			(layer "F.Fab")
		)
		(pad "1" thru_hole rect
			(at 0 0 180)
			(size 1.524 1.524)
			(drill 1.016)
			(layers "*.Cu" "*.Mask")
			(remove_unused_layers no)
			(net "SW_P12V_AUX_PVDDCR_CPU0_P0_FLT")
			(clearance 0)
			(padstack
				(mode front_inner_back)
				(layer "Inner"
					(shape circle)
					(size 1.524 1.524)
					(clearance 0)
				)
				(layer "B.Cu"
					(shape rect)
					(size 1.524 1.524)
					(clearance 0)
				)
			)
		)
		(pad "2" thru_hole circle
			(at 0 2.500122 180)
			(size 1.524 1.524)
			(drill 1.016)
			(layers "*.Cu" "*.Mask")
			(remove_unused_layers no)
			(net "GND")
			(clearance 0)
		)
	)
)
